# SCM (Grand Teton) — schematic netlist excerpt (pin names and nets, part order shuffled) for the footprints in the layout excerpt that follows; sources: Cadence DE-HDL packaged netlist, KiCad conversion of 12092022_DA0F0TMDCD0_F0T_Management_Board_D_brd_V3_OCP.brd

R652  Q_RES  33.2 1% EMPTY  pkg 0402LF  page 21 : A = BMC_EMMC_DT5 ; B = EMMC_DT5_R
R447  Q_RES  0 5% CHIP  pkg 0402LF  page 34 : A = RST_EXTRST_R_N ; B = RST_EXTRST_N

(kicad_pcb
	(version 20260206)
	(generator "pcbnew")
	(generator_version "10.0")
	(general
		(thickness 1.6)
		(legacy_teardrops no)
	)
	(paper "A4")
	(title_block
		(title "12092022_DA0F0TMDCD0_F0T_Management_Board_D_brd_V3_OCP.brd")
		(comment 1 "Grand Teton / footprints 402-403 of 1440")
	)
	(layers
		(0 "F.Cu" signal "TOP")
		(4 "In1.Cu" signal "GND")
		(6 "In2.Cu" signal "IN1")
		(8 "In3.Cu" signal "GND1")
		(10 "In4.Cu" signal "IN2")
		(12 "In5.Cu" signal "VCC")
		(14 "In6.Cu" signal "VCC1")
		(16 "In7.Cu" signal "IN3")
		(18 "In8.Cu" signal "GND2")
		(20 "In9.Cu" signal "IN4")
		(22 "In10.Cu" signal "GND3")
		(2 "B.Cu" signal "BOTTOM")
		(9 "F.Adhes" user "F.Adhesive")
		(11 "B.Adhes" user "B.Adhesive")
		(13 "F.Paste" user "Package Geometry/Pastemask Top")
		(15 "B.Paste" user "Package Geometry/Pastemask Bottom")
		(5 "F.SilkS" user "Ref Des/Silkscreen Top")
		(7 "B.SilkS" user "Ref Des/Silkscreen Bottom")
		(1 "F.Mask" user "Board Geometry/Soldermask Top")
		(3 "B.Mask" user "Board Geometry/Soldermask Bottom")
		(17 "Dwgs.User" user "User.Drawings")
		(19 "Cmts.User" user "User.Comments")
		(21 "Eco1.User" user "User.Eco1")
		(23 "Eco2.User" user "User.Eco2")
		(25 "Edge.Cuts" user "Board Geometry/Outline")
		(27 "Margin" user)
		(31 "F.CrtYd" user "Package Geometry/Place Bound Top")
		(29 "B.CrtYd" user "Package Geometry/Place Bound Bottom")
		(35 "F.Fab" user "Ref Des/Assembly Top")
		(33 "B.Fab" user "Ref Des/Assembly Bottom")
	)
	(footprint ""
		(layer "F.Cu")
		(at 17.4752 -83.7692 -90)
		(property "Reference" "R447"
			(at 0 0 270)
			(layer "F.SilkS")
			(hide yes)
			(effects
				(font
					(size 1.27 1.27)
				)
			)
		)
		(property "Value" ""
			(at 0 0 270)
			(layer "F.Fab")
			(effects
				(font
					(size 1.27 1.27)
				)
			)
		)
		(duplicate_pad_numbers_are_jumpers no)
		(fp_line
			(start -0.7874 0.4064)
			(end -0.7874 -0.4064)
			(stroke
				(width 0.1524)
				(type default)
			)
			(layer "F.SilkS")
		)
		(fp_line
			(start 0.7874 0.4064)
			(end -0.7874 0.4064)
			(stroke
				(width 0.1524)
				(type default)
			)
			(layer "F.SilkS")
		)
		(fp_line
			(start -0.7874 -0.4064)
			(end 0.7874 -0.4064)
			(stroke
				(width 0.1524)
				(type default)
			)
			(layer "F.SilkS")
		)
		(fp_line
			(start 0.7874 -0.4064)
			(end 0.7874 0.4064)
			(stroke
				(width 0.1524)
				(type default)
			)
			(layer "F.SilkS")
		)
		(fp_line
			(start -0.67945 0.3048)
			(end -0.67945 -0.305054)
			(stroke
				(width 0.1)
				(type default)
			)
			(layer "F.Fab")
		)
		(fp_line
			(start -0.12065 0.3048)
			(end -0.67945 0.3048)
			(stroke
				(width 0.1)
				(type default)
			)
			(layer "F.Fab")
		)
		(fp_line
			(start 0.120396 0.3048)
			(end 0.120396 0.2794)
			(stroke
				(width 0.1)
				(type default)
			)
			(layer "F.Fab")
		)
		(fp_line
			(start 0.67945 0.3048)
			(end 0.120396 0.3048)
			(stroke
				(width 0.1)
				(type default)
			)
			(layer "F.Fab")
		)
		(fp_line
			(start -0.12065 0.2794)
			(end -0.12065 0.3048)
			(stroke
				(width 0.1)
				(type default)
			)
			(layer "F.Fab")
		)
		(fp_line
			(start 0.120396 0.2794)
			(end -0.12065 0.2794)
			(stroke
				(width 0.1)
				(type default)
			)
			(layer "F.Fab")
		)
		(fp_line
			(start -0.12065 -0.2794)
			(end 0.12065 -0.2794)
			(stroke
				(width 0.1)
				(type default)
			)
			(layer "F.Fab")
		)
		(fp_line
			(start 0.12065 -0.2794)
			(end 0.12065 -0.3048)
			(stroke
				(width 0.1)
				(type default)
			)
			(layer "F.Fab")
		)
		(fp_line
			(start 0.12065 -0.3048)
			(end 0.67945 -0.3048)
			(stroke
				(width 0.1)
				(type default)
			)
			(layer "F.Fab")
		)
		(fp_line
			(start 0.67945 -0.3048)
			(end 0.67945 0.3048)
			(stroke
				(width 0.1)
				(type default)
			)
			(layer "F.Fab")
		)
		(fp_line
			(start -0.67945 -0.305054)
			(end -0.12065 -0.305054)
			(stroke
				(width 0.1)
				(type default)
			)
			(layer "F.Fab")
		)
		(fp_line
			(start -0.12065 -0.305054)
			(end -0.12065 -0.2794)
			(stroke
				(width 0.1)
				(type default)
			)
			(layer "F.Fab")
		)
		(pad "1" smd circle
			(at -0.40005 0 270)
			(size 0 0)
			(layers "F.Cu" "F.Mask" "F.Paste")
			(net "RST_EXTRST_R_N")
		)
		(pad "2" smd circle
			(at 0.40005 0 270)
			(size 0 0)
			(layers "F.Cu" "F.Mask" "F.Paste")
			(net "RST_EXTRST_N")
		)
	)
	(footprint ""
		(layer "F.Cu")
		(at 31.56204 -68.504054 90)
		(property "Reference" "R652"
			(at 0 0 90)
			(layer "F.SilkS")
			(hide yes)
			(effects
				(font
					(size 1.27 1.27)
				)
			)
		)
		(property "Value" ""
			(at 0 0 90)
			(layer "F.Fab")
			(effects
				(font
					(size 1.27 1.27)
				)
			)
		)
		(duplicate_pad_numbers_are_jumpers no)
		(fp_line
			(start 0.7874 -0.4064)
			(end 0.7874 0.4064)
			(stroke
				(width 0.1524)
				(type default)
			)
			(layer "F.SilkS")
		)
		(fp_line
			(start -0.7874 -0.4064)
			(end 0.7874 -0.4064)
			(stroke
				(width 0.1524)
				(type default)
			)
			(layer "F.SilkS")
		)
		(fp_line
			(start 0.7874 0.4064)
			(end -0.7874 0.4064)
			(stroke
				(width 0.1524)
				(type default)
			)
			(layer "F.SilkS")
		)
		(fp_line
			(start -0.7874 0.4064)
			(end -0.7874 -0.4064)
			(stroke
				(width 0.1524)
				(type default)
			)
			(layer "F.SilkS")
		)
		(fp_line
			(start -0.12065 -0.305054)
			(end -0.12065 -0.2794)
			(stroke
				(width 0.1)
				(type default)
			)
			(layer "F.Fab")
		)
		(fp_line
			(start -0.67945 -0.305054)
			(end -0.12065 -0.305054)
			(stroke
				(width 0.1)
				(type default)
			)
			(layer "F.Fab")
		)
		(fp_line
			(start 0.67945 -0.3048)
			(end 0.67945 0.3048)
			(stroke
				(width 0.1)
				(type default)
			)
			(layer "F.Fab")
		)
		(fp_line
			(start 0.12065 -0.3048)
			(end 0.67945 -0.3048)
			(stroke
				(width 0.1)
				(type default)
			)
			(layer "F.Fab")
		)
		(fp_line
			(start 0.12065 -0.2794)
			(end 0.12065 -0.3048)
			(stroke
				(width 0.1)
				(type default)
			)
			(layer "F.Fab")
		)
		(fp_line
			(start -0.12065 -0.2794)
			(end 0.12065 -0.2794)
			(stroke
				(width 0.1)
				(type default)
			)
			(layer "F.Fab")
		)
		(fp_line
			(start 0.120396 0.2794)
			(end -0.12065 0.2794)
			(stroke
				(width 0.1)
				(type default)
			)
			(layer "F.Fab")
		)
		(fp_line
			(start -0.12065 0.2794)
			(end -0.12065 0.3048)
			(stroke
				(width 0.1)
				(type default)
			)
			(layer "F.Fab")
		)
		(fp_line
			(start 0.67945 0.3048)
			(end 0.120396 0.3048)
			(stroke
				(width 0.1)
				(type default)
			)
			(layer "F.Fab")
		)
		(fp_line
			(start 0.120396 0.3048)
			(end 0.120396 0.2794)
			(stroke
				(width 0.1)
				(type default)
			)
			(layer "F.Fab")
		)
		(fp_line
			(start -0.12065 0.3048)
			(end -0.67945 0.3048)
			(stroke
				(width 0.1)
				(type default)
			)
			(layer "F.Fab")
		)
		(fp_line
			(start -0.67945 0.3048)
			(end -0.67945 -0.305054)
			(stroke
				(width 0.1)
				(type default)
			)
			(layer "F.Fab")
		)
		(pad "1" smd circle
			(at -0.40005 0 90)
			(size 0 0)
			(layers "F.Cu" "F.Mask" "F.Paste")
			(net "BMC_EMMC_DT5")
		)
		(pad "2" smd circle
			(at 0.40005 0 90)
			(size 0 0)
			(layers "F.Cu" "F.Mask" "F.Paste")
			(net "EMMC_DT5_R")
		)
	)
)
